(kicad_pcb
	(version 20241229)
	(generator "pcbnew")
	(generator_version "9.0")
	(general
		(thickness 1.62)
		(legacy_teardrops no)
	)
	(paper "A3")
	(title_block
		(title "COM Express 7 Baseboard")
		(date "2025-02-04")
		(rev "1.1.2")
		(company "Antmicro Ltd")
		(comment 1 "www.antmicro.com")
		(comment 9 "footprints 503-508 of 802")
	)
	(layers
		(0 "F.Cu" signal)
		(4 "In1.Cu" signal)
		(6 "In2.Cu" signal)
		(8 "In3.Cu" signal)
		(10 "In4.Cu" signal)
		(12 "In5.Cu" signal)
		(14 "In6.Cu" signal)
		(2 "B.Cu" signal)
		(9 "F.Adhes" user "F.Adhesive")
		(11 "B.Adhes" user "B.Adhesive")
		(13 "F.Paste" user)
		(15 "B.Paste" user)
		(5 "F.SilkS" user "F.Silkscreen")
		(7 "B.SilkS" user "B.Silkscreen")
		(1 "F.Mask" user)
		(3 "B.Mask" user)
		(17 "Dwgs.User" user "User.Drawings")
		(19 "Cmts.User" user "User.Comments")
		(21 "Eco1.User" user "User.Eco1")
		(23 "Eco2.User" user "User.Eco2")
		(25 "Edge.Cuts" user)
		(27 "Margin" user)
		(31 "F.CrtYd" user "F.Courtyard")
		(29 "B.CrtYd" user "B.Courtyard")
		(35 "F.Fab" user)
		(33 "B.Fab" user)
	)
	(footprint "antmicro-footprints:R_0402_1005Metric"
		(layer "F.Cu")
		(at 252.665 89.449999)
		(descr "Resistor SMD 0402")
		(tags "resistor SMD 0402")
		(property "Reference" "R151"
			(at -0.865 0.440001 0)
			(layer "F.SilkS")
			(effects
				(font
					(size 0.7 0.7)
					(thickness 0.15)
				)
				(justify right bottom)
			)
		)
		(property "Value" "R_0R_0402"
			(at -1.011843 1.772047 0)
			(layer "F.Fab")
			(effects
				(font
					(size 0.7 0.7)
					(thickness 0.15)
				)
				(justify left bottom)
			)
		)
		(property "Datasheet" "https://industrial.panasonic.com/cdbs/www-data/pdf/RDA0000/AOA0000C301.pdf"
			(at 0 0 0)
			(layer "F.Fab")
			(hide yes)
			(effects
				(font
					(size 1.27 1.27)
					(thickness 0.15)
				)
			)
		)
		(property "Author" "Antmicro"
			(at 0 0 0)
			(layer "F.Fab")
			(hide yes)
			(effects
				(font
					(size 1 1)
					(thickness 0.15)
				)
			)
		)
		(property "Current" "1A"
			(at 0 0 0)
			(layer "F.Fab")
			(hide yes)
			(effects
				(font
					(size 1 1)
					(thickness 0.15)
				)
			)
		)
		(property "License" "Apache-2.0"
			(at 0 0 0)
			(layer "F.Fab")
			(hide yes)
			(effects
				(font
					(size 1 1)
					(thickness 0.15)
				)
			)
		)
		(property "MPN" "ERJ2GE0R00X"
			(at 0 0 0)
			(layer "F.Fab")
			(hide yes)
			(effects
				(font
					(size 1 1)
					(thickness 0.15)
				)
			)
		)
		(property "Manufacturer" "Panasonic"
			(at 0 0 0)
			(layer "F.Fab")
			(hide yes)
			(effects
				(font
					(size 1 1)
					(thickness 0.15)
				)
			)
		)
		(property "Public" "False"
			(at 0 0 0)
			(layer "F.Fab")
			(hide yes)
			(effects
				(font
					(size 1 1)
					(thickness 0.15)
				)
			)
		)
		(property "Tolerance" ""
			(at 0 0 0)
			(layer "F.Fab")
			(hide yes)
			(effects
				(font
					(size 1 1)
					(thickness 0.15)
				)
			)
		)
		(property "Val" "0R"
			(at 0 0 0)
			(layer "F.Fab")
			(hide yes)
			(effects
				(font
					(size 1 1)
					(thickness 0.15)
				)
			)
		)
		(sheetname "Misc")
		(sheetfile "misc.kicad_sch")
		(attr smd)
		(fp_rect
			(start -0.925 -0.47)
			(end 0.925 0.47)
			(stroke
				(width 0.05)
				(type default)
			)
			(fill no)
			(layer "F.CrtYd")
		)
		(fp_rect
			(start -0.5 -0.25)
			(end 0.5 0.25)
			(stroke
				(width 0.15)
				(type solid)
			)
			(fill no)
			(layer "F.Fab")
		)
		(pad "1" smd roundrect
			(at -0.48 0)
			(size 0.59 0.64)
			(layers "F.Cu" "F.Mask" "F.Paste")
			(roundrect_rratio 0.25)
			(net 78 "+1V8")
			(pintype "passive")
			(teardrops
				(best_length_ratio 0.2)
				(max_length 1)
				(best_width_ratio 0.9)
				(max_width 2)
				(curved_edges yes)
				(filter_ratio 0.9)
				(enabled yes)
				(allow_two_segments yes)
				(prefer_zone_connections yes)
			)
		)
		(pad "2" smd roundrect
			(at 0.48 0)
			(size 0.59 0.64)
			(layers "F.Cu" "F.Mask" "F.Paste")
			(roundrect_rratio 0.25)
			(net 593 "Net-(U24-V_{CCP})")
			(pintype "passive")
			(teardrops
				(best_length_ratio 0.2)
				(max_length 1)
				(best_width_ratio 0.9)
				(max_width 2)
				(curved_edges yes)
				(filter_ratio 0.9)
				(enabled yes)
				(allow_two_segments yes)
				(prefer_zone_connections yes)
			)
		)
	)
	(footprint "antmicro-footprints:TP_SMD_0.75mm"
		(layer "F.Cu")
		(at 193.70861 72.802163 -90)
		(property "Reference" "TP102"
			(at 0 -0.6 90)
			(layer "F.SilkS")
			(hide yes)
			(effects
				(font
					(size 0.7 0.7)
					(thickness 0.15)
				)
				(justify right bottom)
			)
		)
		(property "Value" "TP_0.75mm_SMD"
			(at 0 1.2 90)
			(layer "F.Fab")
			(effects
				(font
					(size 0.7 0.7)
					(thickness 0.15)
				)
				(justify right bottom)
			)
		)
		(property "Author" "Antmicro"
			(at 120.906447 266.510773 0)
			(layer "F.Fab")
			(hide yes)
			(effects
				(font
					(size 1 1)
					(thickness 0.15)
				)
			)
		)
		(property "License" "Apache-2.0"
			(at 120.906447 266.510773 0)
			(layer "F.Fab")
			(hide yes)
			(effects
				(font
					(size 1 1)
					(thickness 0.15)
				)
			)
		)
		(property "MPN" ""
			(at 120.906447 266.510773 0)
			(layer "F.Fab")
			(hide yes)
			(effects
				(font
					(size 1 1)
					(thickness 0.15)
				)
			)
		)
		(property "Manufacturer" ""
			(at 120.906447 266.510773 0)
			(layer "F.Fab")
			(hide yes)
			(effects
				(font
					(size 1 1)
					(thickness 0.15)
				)
			)
		)
		(property "Public" "False"
			(at 120.906447 266.510773 0)
			(layer "F.Fab")
			(hide yes)
			(effects
				(font
					(size 1 1)
					(thickness 0.15)
				)
			)
		)
		(sheetname "Power")
		(sheetfile "power.kicad_sch")
		(attr exclude_from_pos_files exclude_from_bom)
		(fp_circle
			(center 0 0)
			(end 0.475 0)
			(stroke
				(width 0.05)
				(type default)
			)
			(fill no)
			(layer "F.CrtYd")
		)
		(pad "1" smd circle
			(at 0 0 270)
			(size 0.75 0.75)
			(layers "F.Cu" "F.Mask")
			(net 65 "+12V")
			(pinfunction "1")
			(pintype "passive")
			(teardrops
				(best_length_ratio 0.4)
				(max_length 1)
				(best_width_ratio 0.9)
				(max_width 2)
				(curved_edges yes)
				(filter_ratio 0.9)
				(enabled yes)
				(allow_two_segments yes)
				(prefer_zone_connections yes)
			)
		)
	)
	(footprint "antmicro-footprints:C_0402_1005Metric"
		(layer "F.Cu")
		(at 124.84 140.86)
		(descr "Capacitor SMD 0402")
		(tags "capacitor SMD 0402")
		(property "Reference" "C178"
			(at -3.69 0.45 180)
			(layer "F.SilkS")
			(effects
				(font
					(size 0.7 0.7)
					(thickness 0.15)
				)
				(justify left bottom)
			)
		)
		(property "Value" "C_100n_0402"
			(at -1.022927 2.155213 0)
			(layer "F.Fab")
			(effects
				(font
					(size 0.7 0.7)
					(thickness 0.15)
				)
				(justify left bottom)
			)
		)
		(property "Datasheet" "https://www.murata.com/products/productdetail?partno=GRM155R61H104KE14%23"
			(at 0 0 0)
			(layer "F.Fab")
			(hide yes)
			(effects
				(font
					(size 1.27 1.27)
					(thickness 0.15)
				)
			)
		)
		(property "Author" "Antmicro"
			(at 0 0 0)
			(layer "F.Fab")
			(hide yes)
			(effects
				(font
					(size 1 1)
					(thickness 0.15)
				)
			)
		)
		(property "Dielectric" "X5R"
			(at 0 0 0)
			(layer "F.Fab")
			(hide yes)
			(effects
				(font
					(size 1 1)
					(thickness 0.15)
				)
			)
		)
		(property "License" "Apache-2.0"
			(at 0 0 0)
			(layer "F.Fab")
			(hide yes)
			(effects
				(font
					(size 1 1)
					(thickness 0.15)
				)
			)
		)
		(property "MPN" "GRM155R61H104KE14D"
			(at 0 0 0)
			(layer "F.Fab")
			(hide yes)
			(effects
				(font
					(size 1 1)
					(thickness 0.15)
				)
			)
		)
		(property "Manufacturer" "Murata"
			(at 0 0 0)
			(layer "F.Fab")
			(hide yes)
			(effects
				(font
					(size 1 1)
					(thickness 0.15)
				)
			)
		)
		(property "Public" "False"
			(at 0 0 0)
			(layer "F.Fab")
			(hide yes)
			(effects
				(font
					(size 1 1)
					(thickness 0.15)
				)
			)
		)
		(property "Val" "100n"
			(at 0 0 0)
			(layer "F.Fab")
			(hide yes)
			(effects
				(font
					(size 1 1)
					(thickness 0.15)
				)
			)
		)
		(property "Voltage" "50V"
			(at 0 0 0)
			(layer "F.Fab")
			(hide yes)
			(effects
				(font
					(size 1 1)
					(thickness 0.15)
				)
			)
		)
		(sheetname "KR to SFI #2")
		(sheetfile "kr_sfi.kicad_sch")
		(attr smd)
		(fp_rect
			(start -0.925 -0.47)
			(end 0.925 0.47)
			(stroke
				(width 0.05)
				(type default)
			)
			(fill no)
			(layer "F.CrtYd")
		)
		(fp_line
			(start -0.494 -0.25)
			(end 0.504 -0.25)
			(stroke
				(width 0.15)
				(type solid)
			)
			(layer "F.Fab")
		)
		(fp_line
			(start -0.494 0.248)
			(end -0.494 -0.25)
			(stroke
				(width 0.15)
				(type solid)
			)
			(layer "F.Fab")
		)
		(fp_line
			(start 0.504 -0.25)
			(end 0.504 0.248)
			(stroke
				(width 0.15)
				(type solid)
			)
			(layer "F.Fab")
		)
		(fp_line
			(start 0.504 0.248)
			(end -0.494 0.248)
			(stroke
				(width 0.15)
				(type solid)
			)
			(layer "F.Fab")
		)
		(pad "1" smd roundrect
			(at -0.48 0)
			(size 0.59 0.64)
			(layers "F.Cu" "F.Mask" "F.Paste")
			(roundrect_rratio 0.25)
			(net 117 "/2xSFP+/KR to SFI #2/CLK-")
			(pintype "passive")
			(teardrops
				(best_length_ratio 0.2)
				(max_length 1)
				(best_width_ratio 0.9)
				(max_width 2)
				(curved_edges yes)
				(filter_ratio 0.9)
				(enabled yes)
				(allow_two_segments yes)
				(prefer_zone_connections yes)
			)
		)
		(pad "2" smd roundrect
			(at 0.48 0)
			(size 0.59 0.64)
			(layers "F.Cu" "F.Mask" "F.Paste")
			(roundrect_rratio 0.25)
			(net 116 "/2xSFP+/KR to SFI #2/REFCLK+")
			(pintype "passive")
			(teardrops
				(best_length_ratio 0.2)
				(max_length 1)
				(best_width_ratio 0.9)
				(max_width 2)
				(curved_edges yes)
				(filter_ratio 0.9)
				(enabled yes)
				(allow_two_segments yes)
				(prefer_zone_connections yes)
			)
		)
	)
	(footprint "antmicro-footprints:C_0603_1608Metric"
		(layer "F.Cu")
		(at 315.625499 134.21 90)
		(descr "Capacitor SMD 0603")
		(tags "capacitor 0603")
		(property "Reference" "C60"
			(at 1.15 0.474501 90)
			(layer "F.SilkS")
			(effects
				(font
					(size 0.7 0.7)
					(thickness 0.15)
				)
				(justify left bottom)
			)
		)
		(property "Value" "C_22u_16V_0603"
			(at -1.42757 1.770288 90)
			(layer "F.Fab")
			(effects
				(font
					(size 0.7 0.7)
					(thickness 0.15)
				)
				(justify left bottom)
			)
		)
		(property "Datasheet" "https://product.samsungsem.com/mlcc/CL10A226MO7JZN.do"
			(at 0 0 90)
			(layer "F.Fab")
			(hide yes)
			(effects
				(font
					(size 1.27 1.27)
					(thickness 0.15)
				)
			)
		)
		(property "Author" "Antmicro"
			(at 449.835499 -181.415499 0)
			(layer "F.Fab")
			(hide yes)
			(effects
				(font
					(size 1 1)
					(thickness 0.15)
				)
			)
		)
		(property "Dielectric" ""
			(at 449.835499 -181.415499 0)
			(layer "F.Fab")
			(hide yes)
			(effects
				(font
					(size 1 1)
					(thickness 0.15)
				)
			)
		)
		(property "License" "Apache-2.0"
			(at 449.835499 -181.415499 0)
			(layer "F.Fab")
			(hide yes)
			(effects
				(font
					(size 1 1)
					(thickness 0.15)
				)
			)
		)
		(property "MPN" "CL10A226MO7JZNC"
			(at 449.835499 -181.415499 0)
			(layer "F.Fab")
			(hide yes)
			(effects
				(font
					(size 1 1)
					(thickness 0.15)
				)
			)
		)
		(property "Manufacturer" "Samsung Electro-Mechanics"
			(at 449.835499 -181.415499 0)
			(layer "F.Fab")
			(hide yes)
			(effects
				(font
					(size 1 1)
					(thickness 0.15)
				)
			)
		)
		(property "Public" "False"
			(at 449.835499 -181.415499 0)
			(layer "F.Fab")
			(hide yes)
			(effects
				(font
					(size 1 1)
					(thickness 0.15)
				)
			)
		)
		(property "Val" "22u"
			(at 449.835499 -181.415499 0)
			(layer "F.Fab")
			(hide yes)
			(effects
				(font
					(size 1 1)
					(thickness 0.15)
				)
			)
		)
		(property "Voltage" "16V"
			(at 449.835499 -181.415499 0)
			(layer "F.Fab")
			(hide yes)
			(effects
				(font
					(size 1 1)
					(thickness 0.15)
				)
			)
		)
		(sheetname "Power")
		(sheetfile "power.kicad_sch")
		(attr smd)
		(fp_line
			(start -0.15 -0.4)
			(end 0.15 -0.4)
			(stroke
				(width 0.15)
				(type solid)
			)
			(layer "F.SilkS")
		)
		(fp_line
			(start -0.15 0.4)
			(end 0.15 0.4)
			(stroke
				(width 0.15)
				(type solid)
			)
			(layer "F.SilkS")
		)
		(fp_rect
			(start -1.25 -0.65)
			(end 1.25 0.65)
			(stroke
				(width 0.05)
				(type solid)
			)
			(fill no)
			(layer "F.CrtYd")
		)
		(fp_rect
			(start -0.8 -0.4)
			(end 0.8 0.4)
			(stroke
				(width 0.15)
				(type solid)
			)
			(fill no)
			(layer "F.Fab")
		)
		(pad "1" smd roundrect
			(at -0.7 0 90)
			(size 0.8 1)
			(layers "F.Cu" "F.Mask" "F.Paste")
			(roundrect_rratio 0.2)
			(net 1 "GND")
			(pintype "passive")
			(teardrops
				(best_length_ratio 0.2)
				(max_length 1)
				(best_width_ratio 0.9)
				(max_width 2)
				(curved_edges yes)
				(filter_ratio 0.9)
				(enabled yes)
				(allow_two_segments yes)
				(prefer_zone_connections yes)
			)
		)
		(pad "2" smd roundrect
			(at 0.7 0 90)
			(size 0.8 1)
			(layers "F.Cu" "F.Mask" "F.Paste")
			(roundrect_rratio 0.2)
			(net 62 "+12V_AON")
			(pintype "passive")
			(teardrops
				(best_length_ratio 0.2)
				(max_length 1)
				(best_width_ratio 0.9)
				(max_width 2)
				(curved_edges yes)
				(filter_ratio 0.9)
				(enabled yes)
				(allow_two_segments yes)
				(prefer_zone_connections yes)
			)
		)
	)
	(footprint "antmicro-footprints:R_0402_1005Metric"
		(layer "F.Cu")
		(at 126.425 83.06 180)
		(descr "Resistor SMD 0402")
		(tags "resistor SMD 0402")
		(property "Reference" "R238"
			(at -1.575 -6.4 0)
			(layer "F.SilkS")
			(effects
				(font
					(size 0.7 0.7)
					(thickness 0.15)
				)
				(justify right bottom)
			)
		)
		(property "Value" "R_0R_0402"
			(at -1.011843 1.772047 0)
			(layer "F.Fab")
			(effects
				(font
					(size 0.7 0.7)
					(thickness 0.15)
				)
				(justify right bottom)
			)
		)
		(property "Datasheet" "https://industrial.panasonic.com/cdbs/www-data/pdf/RDA0000/AOA0000C301.pdf"
			(at 0 0 180)
			(layer "F.Fab")
			(hide yes)
			(effects
				(font
					(size 1.27 1.27)
					(thickness 0.15)
				)
			)
		)
		(property "Author" "Antmicro"
			(at 252.85 166.12 0)
			(layer "F.Fab")
			(hide yes)
			(effects
				(font
					(size 1 1)
					(thickness 0.15)
				)
			)
		)
		(property "Current" "1A"
			(at 252.85 166.12 0)
			(layer "F.Fab")
			(hide yes)
			(effects
				(font
					(size 1 1)
					(thickness 0.15)
				)
			)
		)
		(property "License" "Apache-2.0"
			(at 252.85 166.12 0)
			(layer "F.Fab")
			(hide yes)
			(effects
				(font
					(size 1 1)
					(thickness 0.15)
				)
			)
		)
		(property "MPN" "ERJ2GE0R00X"
			(at 252.85 166.12 0)
			(layer "F.Fab")
			(hide yes)
			(effects
				(font
					(size 1 1)
					(thickness 0.15)
				)
			)
		)
		(property "Manufacturer" "Panasonic"
			(at 252.85 166.12 0)
			(layer "F.Fab")
			(hide yes)
			(effects
				(font
					(size 1 1)
					(thickness 0.15)
				)
			)
		)
		(property "Public" "False"
			(at 252.85 166.12 0)
			(layer "F.Fab")
			(hide yes)
			(effects
				(font
					(size 1 1)
					(thickness 0.15)
				)
			)
		)
		(property "Tolerance" ""
			(at 252.85 166.12 0)
			(layer "F.Fab")
			(hide yes)
			(effects
				(font
					(size 1 1)
					(thickness 0.15)
				)
			)
		)
		(property "Val" "0R"
			(at 252.85 166.12 0)
			(layer "F.Fab")
			(hide yes)
			(effects
				(font
					(size 1 1)
					(thickness 0.15)
				)
			)
		)
		(sheetname "GPIO expander")
		(sheetfile "gpio_exp.kicad_sch")
		(attr smd)
		(fp_rect
			(start -0.925 -0.47)
			(end 0.925 0.47)
			(stroke
				(width 0.05)
				(type default)
			)
			(fill no)
			(layer "F.CrtYd")
		)
		(fp_rect
			(start -0.5 -0.25)
			(end 0.5 0.25)
			(stroke
				(width 0.15)
				(type solid)
			)
			(fill no)
			(layer "F.Fab")
		)
		(pad "1" smd roundrect
			(at -0.48 0 180)
			(size 0.59 0.64)
			(layers "F.Cu" "F.Mask" "F.Paste")
			(roundrect_rratio 0.25)
			(net 639 "Net-(U41-IO0_0)")
			(pintype "passive")
			(teardrops
				(best_length_ratio 0.2)
				(max_length 1)
				(best_width_ratio 0.9)
				(max_width 2)
				(curved_edges yes)
				(filter_ratio 0.9)
				(enabled yes)
				(allow_two_segments yes)
				(prefer_zone_connections yes)
			)
		)
		(pad "2" smd roundrect
			(at 0.48 0 180)
			(size 0.59 0.64)
			(layers "F.Cu" "F.Mask" "F.Paste")
			(roundrect_rratio 0.25)
			(net 573 "/GPIO expander/GPIOEX0")
			(pintype "passive")
			(teardrops
				(best_length_ratio 0.2)
				(max_length 1)
				(best_width_ratio 0.9)
				(max_width 2)
				(curved_edges yes)
				(filter_ratio 0.9)
				(enabled yes)
				(allow_two_segments yes)
				(prefer_zone_connections yes)
			)
		)
	)
	(footprint "antmicro-footprints:C_0402_1005Metric"
		(layer "F.Cu")
		(at 258.325 126.701748 90)
		(descr "Capacitor SMD 0402")
		(tags "capacitor SMD 0402")
		(property "Reference" "C98"
			(at -1.108252 1.325 90)
			(layer "F.SilkS")
			(effects
				(font
					(size 0.7 0.7)
					(thickness 0.15)
				)
				(justify left bottom)
			)
		)
		(property "Value" "C_1u_25V_0402"
			(at -1.022927 2.155213 90)
			(layer "F.Fab")
			(effects
				(font
					(size 0.7 0.7)
					(thickness 0.15)
				)
				(justify left bottom)
			)
		)
		(property "Datasheet" "https://www.murata.com/products/productdetail?partno=GRM155R61E105KE11%23"
			(at 0 0 90)
			(layer "F.Fab")
			(hide yes)
			(effects
				(font
					(size 1.27 1.27)
					(thickness 0.15)
				)
			)
		)
		(property "Description" "SMD Multilayer Ceramic Capacitor, 1 µF, 25 V, 0402 [1005 Metric], ± 10%, X5R, GRM Series"
			(at 0 0 90)
			(layer "F.Fab")
			(hide yes)
			(effects
				(font
					(size 1.27 1.27)
					(thickness 0.15)
				)
			)
		)
		(property "Author" "Antmicro"
			(at 385.026748 -131.623252 0)
			(layer "F.Fab")
			(hide yes)
			(effects
				(font
					(size 1 1)
					(thickness 0.15)
				)
			)
		)
		(property "Dielectric" "X5R"
			(at 385.026748 -131.623252 0)
			(layer "F.Fab")
			(hide yes)
			(effects
				(font
					(size 1 1)
					(thickness 0.15)
				)
			)
		)
		(property "License" "Apache-2.0"
			(at 385.026748 -131.623252 0)
			(layer "F.Fab")
			(hide yes)
			(effects
				(font
					(size 1 1)
					(thickness 0.15)
				)
			)
		)
		(property "MPN" "GRM155R61E105KE11J"
			(at 385.026748 -131.623252 0)
			(layer "F.Fab")
			(hide yes)
			(effects
				(font
					(size 1 1)
					(thickness 0.15)
				)
			)
		)
		(property "Manufacturer" "Murata"
			(at 385.026748 -131.623252 0)
			(layer "F.Fab")
			(hide yes)
			(effects
				(font
					(size 1 1)
					(thickness 0.15)
				)
			)
		)
		(property "Val" "1u"
			(at 385.026748 -131.623252 0)
			(layer "F.Fab")
			(hide yes)
			(effects
				(font
					(size 1 1)
					(thickness 0.15)
				)
			)
		)
		(property "Voltage" "25V"
			(at 385.026748 -131.623252 0)
			(layer "F.Fab")
			(hide yes)
			(effects
				(font
					(size 1 1)
					(thickness 0.15)
				)
			)
		)
		(sheetname "Com Express 7 MGMT")
		(sheetfile "com_express_7_mgmt.kicad_sch")
		(attr smd)
		(fp_rect
			(start -0.925 -0.47)
			(end 0.925 0.47)
			(stroke
				(width 0.05)
				(type default)
			)
			(fill no)
			(layer "F.CrtYd")
		)
		(fp_line
			(start 0.504 -0.25)
			(end 0.504 0.248)
			(stroke
				(width 0.15)
				(type solid)
			)
			(layer "F.Fab")
		)
		(fp_line
			(start -0.494 -0.25)
			(end 0.504 -0.25)
			(stroke
				(width 0.15)
				(type solid)
			)
			(layer "F.Fab")
		)
		(fp_line
			(start 0.504 0.248)
			(end -0.494 0.248)
			(stroke
				(width 0.15)
				(type solid)
			)
			(layer "F.Fab")
		)
		(fp_line
			(start -0.494 0.248)
			(end -0.494 -0.25)
			(stroke
				(width 0.15)
				(type solid)
			)
			(layer "F.Fab")
		)
		(pad "1" smd roundrect
			(at -0.48 0 90)
			(size 0.59 0.64)
			(layers "F.Cu" "F.Mask" "F.Paste")
			(roundrect_rratio 0.25)
			(net 1 "GND")
			(pintype "passive")
			(teardrops
				(best_length_ratio 0.2)
				(max_length 1)
				(best_width_ratio 0.9)
				(max_width 2)
				(curved_edges yes)
				(filter_ratio 0.9)
				(enabled yes)
				(allow_two_segments yes)
				(prefer_zone_connections yes)
			)
		)
		(pad "2" smd roundrect
			(at 0.48 0 90)
			(size 0.59 0.64)
			(layers "F.Cu" "F.Mask" "F.Paste")
			(roundrect_rratio 0.25)
			(net 82 "Net-(U32-CT)")
			(pintype "passive")
			(teardrops
				(best_length_ratio 0.2)
				(max_length 1)
				(best_width_ratio 0.9)
				(max_width 2)
				(curved_edges yes)
				(filter_ratio 0.9)
				(enabled yes)
				(allow_two_segments yes)
				(prefer_zone_connections yes)
			)
		)
	)
)
